(kicad_pcb
	(version 20260206)
	(generator "pcbnew")
	(generator_version "10.0")
	(general
		(thickness 1.6)
		(legacy_teardrops no)
	)
	(paper "A4")
	(title_block
		(title "04192023_DAF0TMB3IC0_F0TG_MB_C_brd_V02_OCP.brd")
		(comment 1 "Grand Teton / footprints 4878-4885 of 8354")
	)
	(layers
		(0 "F.Cu" signal "TOP")
		(4 "In1.Cu" signal "GND")
		(6 "In2.Cu" signal "IN1")
		(8 "In3.Cu" signal "GND1")
		(10 "In4.Cu" signal "IN2")
		(12 "In5.Cu" signal "GND2")
		(14 "In6.Cu" signal "IN3")
		(16 "In7.Cu" signal "GND3")
		(18 "In8.Cu" signal "VCC")
		(20 "In9.Cu" signal "VCC1")
		(22 "In10.Cu" signal "GND4")
		(24 "In11.Cu" signal "IN4")
		(26 "In12.Cu" signal "GND5")
		(28 "In13.Cu" signal "IN5")
		(30 "In14.Cu" signal "GND6")
		(32 "In15.Cu" signal "IN6")
		(34 "In16.Cu" signal "GND7")
		(2 "B.Cu" signal "BOTTOM")
		(9 "F.Adhes" user "F.Adhesive")
		(11 "B.Adhes" user "B.Adhesive")
		(13 "F.Paste" user "Package Geometry/Pastemask Top")
		(15 "B.Paste" user "Package Geometry/Pastemask Bottom")
		(5 "F.SilkS" user "Ref Des/Silkscreen Top")
		(7 "B.SilkS" user "Ref Des/Silkscreen Bottom")
		(1 "F.Mask" user "Board Geometry/Soldermask Top")
		(3 "B.Mask" user "Board Geometry/Soldermask Bottom")
		(17 "Dwgs.User" user "User.Drawings")
		(19 "Cmts.User" user "User.Comments")
		(21 "Eco1.User" user "User.Eco1")
		(23 "Eco2.User" user "User.Eco2")
		(25 "Edge.Cuts" user "Board Geometry/Outline")
		(27 "Margin" user)
		(31 "F.CrtYd" user "Package Geometry/Place Bound Top")
		(29 "B.CrtYd" user "Package Geometry/Place Bound Bottom")
		(35 "F.Fab" user "Ref Des/Assembly Top")
		(33 "B.Fab" user "Ref Des/Assembly Bottom")
	)
	(footprint ""
		(layer "F.Cu")
		(at 112.672876 -418.090858 -90)
		(property "Reference" "R3029"
			(at 0 0 270)
			(layer "F.SilkS")
			(hide yes)
			(effects
				(font
					(size 1.27 1.27)
				)
			)
		)
		(property "Value" ""
			(at 0 0 270)
			(layer "F.Fab")
			(effects
				(font
					(size 1.27 1.27)
				)
			)
		)
		(duplicate_pad_numbers_are_jumpers no)
		(fp_line
			(start -0.7874 0.4064)
			(end -0.7874 -0.4064)
			(stroke
				(width 0.1524)
				(type default)
			)
			(layer "F.SilkS")
		)
		(fp_line
			(start 0.7874 0.4064)
			(end -0.7874 0.4064)
			(stroke
				(width 0.1524)
				(type default)
			)
			(layer "F.SilkS")
		)
		(fp_line
			(start -0.7874 -0.4064)
			(end 0.7874 -0.4064)
			(stroke
				(width 0.1524)
				(type default)
			)
			(layer "F.SilkS")
		)
		(fp_line
			(start 0.7874 -0.4064)
			(end 0.7874 0.4064)
			(stroke
				(width 0.1524)
				(type default)
			)
			(layer "F.SilkS")
		)
		(fp_line
			(start -0.67945 0.3048)
			(end -0.67945 -0.305054)
			(stroke
				(width 0.1)
				(type default)
			)
			(layer "F.Fab")
		)
		(fp_line
			(start -0.12065 0.3048)
			(end -0.67945 0.3048)
			(stroke
				(width 0.1)
				(type default)
			)
			(layer "F.Fab")
		)
		(fp_line
			(start 0.120396 0.3048)
			(end 0.120396 0.2794)
			(stroke
				(width 0.1)
				(type default)
			)
			(layer "F.Fab")
		)
		(fp_line
			(start 0.67945 0.3048)
			(end 0.120396 0.3048)
			(stroke
				(width 0.1)
				(type default)
			)
			(layer "F.Fab")
		)
		(fp_line
			(start -0.12065 0.2794)
			(end -0.12065 0.3048)
			(stroke
				(width 0.1)
				(type default)
			)
			(layer "F.Fab")
		)
		(fp_line
			(start 0.120396 0.2794)
			(end -0.12065 0.2794)
			(stroke
				(width 0.1)
				(type default)
			)
			(layer "F.Fab")
		)
		(fp_line
			(start -0.12065 -0.2794)
			(end 0.12065 -0.2794)
			(stroke
				(width 0.1)
				(type default)
			)
			(layer "F.Fab")
		)
		(fp_line
			(start 0.12065 -0.2794)
			(end 0.12065 -0.3048)
			(stroke
				(width 0.1)
				(type default)
			)
			(layer "F.Fab")
		)
		(fp_line
			(start 0.12065 -0.3048)
			(end 0.67945 -0.3048)
			(stroke
				(width 0.1)
				(type default)
			)
			(layer "F.Fab")
		)
		(fp_line
			(start 0.67945 -0.3048)
			(end 0.67945 0.3048)
			(stroke
				(width 0.1)
				(type default)
			)
			(layer "F.Fab")
		)
		(fp_line
			(start -0.67945 -0.305054)
			(end -0.12065 -0.305054)
			(stroke
				(width 0.1)
				(type default)
			)
			(layer "F.Fab")
		)
		(fp_line
			(start -0.12065 -0.305054)
			(end -0.12065 -0.2794)
			(stroke
				(width 0.1)
				(type default)
			)
			(layer "F.Fab")
		)
		(pad "1" smd circle
			(at -0.40005 0 270)
			(size 0 0)
			(layers "F.Cu" "F.Mask" "F.Paste")
			(net "P3V3_AUX")
		)
		(pad "2" smd circle
			(at 0.40005 0 270)
			(size 0 0)
			(layers "F.Cu" "F.Mask" "F.Paste")
			(net "FM_SMB_1_ALERT_GPU")
		)
	)
	(footprint ""
		(layer "F.Cu")
		(at 142.367 -120.269 180)
		(property "Reference" "R8123"
			(at 0 0 180)
			(layer "F.SilkS")
			(hide yes)
			(effects
				(font
					(size 1.27 1.27)
				)
			)
		)
		(property "Value" ""
			(at 0 0 180)
			(layer "F.Fab")
			(effects
				(font
					(size 1.27 1.27)
				)
			)
		)
		(duplicate_pad_numbers_are_jumpers no)
		(fp_line
			(start 0.7874 0.4064)
			(end -0.7874 0.4064)
			(stroke
				(width 0.1524)
				(type default)
			)
			(layer "F.SilkS")
		)
		(fp_line
			(start 0.7874 -0.4064)
			(end 0.7874 0.4064)
			(stroke
				(width 0.1524)
				(type default)
			)
			(layer "F.SilkS")
		)
		(fp_line
			(start -0.7874 0.4064)
			(end -0.7874 -0.4064)
			(stroke
				(width 0.1524)
				(type default)
			)
			(layer "F.SilkS")
		)
		(fp_line
			(start -0.7874 -0.4064)
			(end 0.7874 -0.4064)
			(stroke
				(width 0.1524)
				(type default)
			)
			(layer "F.SilkS")
		)
		(fp_line
			(start 0.67945 0.3048)
			(end 0.120396 0.3048)
			(stroke
				(width 0.1)
				(type default)
			)
			(layer "F.Fab")
		)
		(fp_line
			(start 0.67945 -0.3048)
			(end 0.67945 0.3048)
			(stroke
				(width 0.1)
				(type default)
			)
			(layer "F.Fab")
		)
		(fp_line
			(start 0.12065 -0.2794)
			(end 0.12065 -0.3048)
			(stroke
				(width 0.1)
				(type default)
			)
			(layer "F.Fab")
		)
		(fp_line
			(start 0.12065 -0.3048)
			(end 0.67945 -0.3048)
			(stroke
				(width 0.1)
				(type default)
			)
			(layer "F.Fab")
		)
		(fp_line
			(start 0.120396 0.3048)
			(end 0.120396 0.2794)
			(stroke
				(width 0.1)
				(type default)
			)
			(layer "F.Fab")
		)
		(fp_line
			(start 0.120396 0.2794)
			(end -0.12065 0.2794)
			(stroke
				(width 0.1)
				(type default)
			)
			(layer "F.Fab")
		)
		(fp_line
			(start -0.12065 0.3048)
			(end -0.67945 0.3048)
			(stroke
				(width 0.1)
				(type default)
			)
			(layer "F.Fab")
		)
		(fp_line
			(start -0.12065 0.2794)
			(end -0.12065 0.3048)
			(stroke
				(width 0.1)
				(type default)
			)
			(layer "F.Fab")
		)
		(fp_line
			(start -0.12065 -0.2794)
			(end 0.12065 -0.2794)
			(stroke
				(width 0.1)
				(type default)
			)
			(layer "F.Fab")
		)
		(fp_line
			(start -0.12065 -0.305054)
			(end -0.12065 -0.2794)
			(stroke
				(width 0.1)
				(type default)
			)
			(layer "F.Fab")
		)
		(fp_line
			(start -0.67945 0.3048)
			(end -0.67945 -0.305054)
			(stroke
				(width 0.1)
				(type default)
			)
			(layer "F.Fab")
		)
		(fp_line
			(start -0.67945 -0.305054)
			(end -0.12065 -0.305054)
			(stroke
				(width 0.1)
				(type default)
			)
			(layer "F.Fab")
		)
		(pad "1" smd circle
			(at -0.40005 0 180)
			(size 0 0)
			(layers "F.Cu" "F.Mask" "F.Paste")
			(net "P12V_AUX_UV_TRIGGER")
		)
		(pad "2" smd circle
			(at 0.40005 0 180)
			(size 0 0)
			(layers "F.Cu" "F.Mask" "F.Paste")
			(net "IRQ_UV_DETECT_R2_N")
		)
	)
	(footprint ""
		(layer "F.Cu")
		(at 118.618 -432.054 180)
		(property "Reference" "R3452"
			(at 0 0 180)
			(layer "F.SilkS")
			(hide yes)
			(effects
				(font
					(size 1.27 1.27)
				)
			)
		)
		(property "Value" ""
			(at 0 0 180)
			(layer "F.Fab")
			(effects
				(font
					(size 1.27 1.27)
				)
			)
		)
		(duplicate_pad_numbers_are_jumpers no)
		(fp_line
			(start 0.7874 0.4064)
			(end -0.7874 0.4064)
			(stroke
				(width 0.1524)
				(type default)
			)
			(layer "F.SilkS")
		)
		(fp_line
			(start 0.7874 -0.4064)
			(end 0.7874 0.4064)
			(stroke
				(width 0.1524)
				(type default)
			)
			(layer "F.SilkS")
		)
		(fp_line
			(start -0.7874 0.4064)
			(end -0.7874 -0.4064)
			(stroke
				(width 0.1524)
				(type default)
			)
			(layer "F.SilkS")
		)
		(fp_line
			(start -0.7874 -0.4064)
			(end 0.7874 -0.4064)
			(stroke
				(width 0.1524)
				(type default)
			)
			(layer "F.SilkS")
		)
		(fp_line
			(start 0.67945 0.3048)
			(end 0.120396 0.3048)
			(stroke
				(width 0.1)
				(type default)
			)
			(layer "F.Fab")
		)
		(fp_line
			(start 0.67945 -0.3048)
			(end 0.67945 0.3048)
			(stroke
				(width 0.1)
				(type default)
			)
			(layer "F.Fab")
		)
		(fp_line
			(start 0.12065 -0.2794)
			(end 0.12065 -0.3048)
			(stroke
				(width 0.1)
				(type default)
			)
			(layer "F.Fab")
		)
		(fp_line
			(start 0.12065 -0.3048)
			(end 0.67945 -0.3048)
			(stroke
				(width 0.1)
				(type default)
			)
			(layer "F.Fab")
		)
		(fp_line
			(start 0.120396 0.3048)
			(end 0.120396 0.2794)
			(stroke
				(width 0.1)
				(type default)
			)
			(layer "F.Fab")
		)
		(fp_line
			(start 0.120396 0.2794)
			(end -0.12065 0.2794)
			(stroke
				(width 0.1)
				(type default)
			)
			(layer "F.Fab")
		)
		(fp_line
			(start -0.12065 0.3048)
			(end -0.67945 0.3048)
			(stroke
				(width 0.1)
				(type default)
			)
			(layer "F.Fab")
		)
		(fp_line
			(start -0.12065 0.2794)
			(end -0.12065 0.3048)
			(stroke
				(width 0.1)
				(type default)
			)
			(layer "F.Fab")
		)
		(fp_line
			(start -0.12065 -0.2794)
			(end 0.12065 -0.2794)
			(stroke
				(width 0.1)
				(type default)
			)
			(layer "F.Fab")
		)
		(fp_line
			(start -0.12065 -0.305054)
			(end -0.12065 -0.2794)
			(stroke
				(width 0.1)
				(type default)
			)
			(layer "F.Fab")
		)
		(fp_line
			(start -0.67945 0.3048)
			(end -0.67945 -0.305054)
			(stroke
				(width 0.1)
				(type default)
			)
			(layer "F.Fab")
		)
		(fp_line
			(start -0.67945 -0.305054)
			(end -0.12065 -0.305054)
			(stroke
				(width 0.1)
				(type default)
			)
			(layer "F.Fab")
		)
		(pad "1" smd circle
			(at -0.40005 0 180)
			(size 0 0)
			(layers "F.Cu" "F.Mask" "F.Paste")
			(net "GPU_BASE_STBY_EN")
		)
		(pad "2" smd circle
			(at 0.40005 0 180)
			(size 0 0)
			(layers "F.Cu" "F.Mask" "F.Paste")
			(net "GND")
		)
	)
	(footprint ""
		(layer "F.Cu")
		(at 411.605222 -416.899344 -90)
		(property "Reference" "C6591"
			(at 0 0 270)
			(layer "F.SilkS")
			(hide yes)
			(effects
				(font
					(size 1.27 1.27)
				)
			)
		)
		(property "Value" ""
			(at 0 0 270)
			(layer "F.Fab")
			(effects
				(font
					(size 1.27 1.27)
				)
			)
		)
		(duplicate_pad_numbers_are_jumpers no)
		(fp_line
			(start -0.299974 0.150114)
			(end -0.299974 -0.150114)
			(stroke
				(width 0.1)
				(type default)
			)
			(layer "F.Fab")
		)
		(fp_line
			(start 0.299974 0.150114)
			(end -0.299974 0.150114)
			(stroke
				(width 0.1)
				(type default)
			)
			(layer "F.Fab")
		)
		(fp_line
			(start -0.299974 -0.150114)
			(end 0.299974 -0.150114)
			(stroke
				(width 0.1)
				(type default)
			)
			(layer "F.Fab")
		)
		(fp_line
			(start 0.299974 -0.150114)
			(end 0.299974 0.150114)
			(stroke
				(width 0.1)
				(type default)
			)
			(layer "F.Fab")
		)
		(pad "1" smd rect
			(at -0.2667 0 270)
			(size 0.3048 0.381)
			(layers "F.Cu" "F.Mask" "F.Paste")
			(net "P5E_CPU0_P2_TX_BUF_C_DP<13>")
		)
		(pad "2" smd rect
			(at 0.2667 0 270)
			(size 0.3048 0.381)
			(layers "F.Cu" "F.Mask" "F.Paste")
			(net "P5E_CPU0_P2_TX_BUF_DP<13>")
		)
	)
	(footprint ""
		(layer "F.Cu")
		(at 297.554142 -400.177)
		(property "Reference" "R997"
			(at 0 0 0)
			(layer "F.SilkS")
			(hide yes)
			(effects
				(font
					(size 1.27 1.27)
				)
			)
		)
		(property "Value" ""
			(at 0 0 0)
			(layer "F.Fab")
			(effects
				(font
					(size 1.27 1.27)
				)
			)
		)
		(duplicate_pad_numbers_are_jumpers no)
		(fp_line
			(start -0.32512 -0.175006)
			(end 0.32512 -0.175006)
			(stroke
				(width 0.1)
				(type default)
			)
			(layer "F.Fab")
		)
		(fp_line
			(start -0.32512 0.175006)
			(end -0.32512 -0.175006)
			(stroke
				(width 0.1)
				(type default)
			)
			(layer "F.Fab")
		)
		(fp_line
			(start 0.32512 -0.175006)
			(end 0.32512 0.175006)
			(stroke
				(width 0.1)
				(type default)
			)
			(layer "F.Fab")
		)
		(fp_line
			(start 0.32512 0.175006)
			(end -0.32512 0.175006)
			(stroke
				(width 0.1)
				(type default)
			)
			(layer "F.Fab")
		)
		(pad "1" smd rect
			(at -0.2667 0)
			(size 0.3048 0.381)
			(layers "F.Cu" "F.Mask" "F.Paste")
			(net "JTAG_TEST_MODE_RT_CPU0_P0")
		)
		(pad "2" smd rect
			(at 0.2667 0 180)
			(size 0.3048 0.381)
			(layers "F.Cu" "F.Mask" "F.Paste")
			(net "GND")
		)
	)
	(footprint ""
		(layer "F.Cu")
		(at 453.719946 -108.059728)
		(property "Reference" "R1905"
			(at 0 0 0)
			(layer "F.SilkS")
			(hide yes)
			(effects
				(font
					(size 1.27 1.27)
				)
			)
		)
		(property "Value" ""
			(at 0 0 0)
			(layer "F.Fab")
			(effects
				(font
					(size 1.27 1.27)
				)
			)
		)
		(duplicate_pad_numbers_are_jumpers no)
		(fp_line
			(start -0.7874 -0.4064)
			(end 0.7874 -0.4064)
			(stroke
				(width 0.1524)
				(type default)
			)
			(layer "F.SilkS")
		)
		(fp_line
			(start -0.7874 0.4064)
			(end -0.7874 -0.4064)
			(stroke
				(width 0.1524)
				(type default)
			)
			(layer "F.SilkS")
		)
		(fp_line
			(start 0.7874 -0.4064)
			(end 0.7874 0.4064)
			(stroke
				(width 0.1524)
				(type default)
			)
			(layer "F.SilkS")
		)
		(fp_line
			(start 0.7874 0.4064)
			(end -0.7874 0.4064)
			(stroke
				(width 0.1524)
				(type default)
			)
			(layer "F.SilkS")
		)
		(fp_line
			(start -0.67945 -0.305054)
			(end -0.12065 -0.305054)
			(stroke
				(width 0.1)
				(type default)
			)
			(layer "F.Fab")
		)
		(fp_line
			(start -0.67945 0.3048)
			(end -0.67945 -0.305054)
			(stroke
				(width 0.1)
				(type default)
			)
			(layer "F.Fab")
		)
		(fp_line
			(start -0.12065 -0.305054)
			(end -0.12065 -0.2794)
			(stroke
				(width 0.1)
				(type default)
			)
			(layer "F.Fab")
		)
		(fp_line
			(start -0.12065 -0.2794)
			(end 0.12065 -0.2794)
			(stroke
				(width 0.1)
				(type default)
			)
			(layer "F.Fab")
		)
		(fp_line
			(start -0.12065 0.2794)
			(end -0.12065 0.3048)
			(stroke
				(width 0.1)
				(type default)
			)
			(layer "F.Fab")
		)
		(fp_line
			(start -0.12065 0.3048)
			(end -0.67945 0.3048)
			(stroke
				(width 0.1)
				(type default)
			)
			(layer "F.Fab")
		)
		(fp_line
			(start 0.120396 0.2794)
			(end -0.12065 0.2794)
			(stroke
				(width 0.1)
				(type default)
			)
			(layer "F.Fab")
		)
		(fp_line
			(start 0.120396 0.3048)
			(end 0.120396 0.2794)
			(stroke
				(width 0.1)
				(type default)
			)
			(layer "F.Fab")
		)
		(fp_line
			(start 0.12065 -0.3048)
			(end 0.67945 -0.3048)
			(stroke
				(width 0.1)
				(type default)
			)
			(layer "F.Fab")
		)
		(fp_line
			(start 0.12065 -0.2794)
			(end 0.12065 -0.3048)
			(stroke
				(width 0.1)
				(type default)
			)
			(layer "F.Fab")
		)
		(fp_line
			(start 0.67945 -0.3048)
			(end 0.67945 0.3048)
			(stroke
				(width 0.1)
				(type default)
			)
			(layer "F.Fab")
		)
		(fp_line
			(start 0.67945 0.3048)
			(end 0.120396 0.3048)
			(stroke
				(width 0.1)
				(type default)
			)
			(layer "F.Fab")
		)
		(pad "1" smd circle
			(at -0.40005 0)
			(size 0 0)
			(layers "F.Cu" "F.Mask" "F.Paste")
			(net "P3V3_AUX")
		)
		(pad "2" smd circle
			(at 0.40005 0)
			(size 0 0)
			(layers "F.Cu" "F.Mask" "F.Paste")
			(net "OCP_SFF_PRSNT0_R_N")
		)
	)
	(footprint ""
		(layer "F.Cu")
		(at 180.721 -100.294948 90)
		(property "Reference" "R189"
			(at 0 0 90)
			(layer "F.SilkS")
			(hide yes)
			(effects
				(font
					(size 1.27 1.27)
				)
			)
		)
		(property "Value" ""
			(at 0 0 90)
			(layer "F.Fab")
			(effects
				(font
					(size 1.27 1.27)
				)
			)
		)
		(duplicate_pad_numbers_are_jumpers no)
		(fp_line
			(start 0.7874 -0.4064)
			(end 0.7874 0.4064)
			(stroke
				(width 0.1524)
				(type default)
			)
			(layer "F.SilkS")
		)
		(fp_line
			(start -0.7874 -0.4064)
			(end 0.7874 -0.4064)
			(stroke
				(width 0.1524)
				(type default)
			)
			(layer "F.SilkS")
		)
		(fp_line
			(start 0.7874 0.4064)
			(end -0.7874 0.4064)
			(stroke
				(width 0.1524)
				(type default)
			)
			(layer "F.SilkS")
		)
		(fp_line
			(start -0.7874 0.4064)
			(end -0.7874 -0.4064)
			(stroke
				(width 0.1524)
				(type default)
			)
			(layer "F.SilkS")
		)
		(fp_line
			(start -0.12065 -0.305054)
			(end -0.12065 -0.2794)
			(stroke
				(width 0.1)
				(type default)
			)
			(layer "F.Fab")
		)
		(fp_line
			(start -0.67945 -0.305054)
			(end -0.12065 -0.305054)
			(stroke
				(width 0.1)
				(type default)
			)
			(layer "F.Fab")
		)
		(fp_line
			(start 0.67945 -0.3048)
			(end 0.67945 0.3048)
			(stroke
				(width 0.1)
				(type default)
			)
			(layer "F.Fab")
		)
		(fp_line
			(start 0.12065 -0.3048)
			(end 0.67945 -0.3048)
			(stroke
				(width 0.1)
				(type default)
			)
			(layer "F.Fab")
		)
		(fp_line
			(start 0.12065 -0.2794)
			(end 0.12065 -0.3048)
			(stroke
				(width 0.1)
				(type default)
			)
			(layer "F.Fab")
		)
		(fp_line
			(start -0.12065 -0.2794)
			(end 0.12065 -0.2794)
			(stroke
				(width 0.1)
				(type default)
			)
			(layer "F.Fab")
		)
		(fp_line
			(start 0.120396 0.2794)
			(end -0.12065 0.2794)
			(stroke
				(width 0.1)
				(type default)
			)
			(layer "F.Fab")
		)
		(fp_line
			(start -0.12065 0.2794)
			(end -0.12065 0.3048)
			(stroke
				(width 0.1)
				(type default)
			)
			(layer "F.Fab")
		)
		(fp_line
			(start 0.67945 0.3048)
			(end 0.120396 0.3048)
			(stroke
				(width 0.1)
				(type default)
			)
			(layer "F.Fab")
		)
		(fp_line
			(start 0.120396 0.3048)
			(end 0.120396 0.2794)
			(stroke
				(width 0.1)
				(type default)
			)
			(layer "F.Fab")
		)
		(fp_line
			(start -0.12065 0.3048)
			(end -0.67945 0.3048)
			(stroke
				(width 0.1)
				(type default)
			)
			(layer "F.Fab")
		)
		(fp_line
			(start -0.67945 0.3048)
			(end -0.67945 -0.305054)
			(stroke
				(width 0.1)
				(type default)
			)
			(layer "F.Fab")
		)
		(pad "1" smd circle
			(at -0.40005 0 90)
			(size 0 0)
			(layers "F.Cu" "F.Mask" "F.Paste")
			(net "FM_BMC_TPM_PRES_N")
		)
		(pad "2" smd circle
			(at 0.40005 0 90)
			(size 0 0)
			(layers "F.Cu" "F.Mask" "F.Paste")
			(net "FM_BMC_TPM_PRES_N_R")
		)
	)
	(footprint ""
		(layer "F.Cu")
		(at 374.598692 -378.95403 -90)
		(property "Reference" "C889"
			(at 0 0 270)
			(layer "F.SilkS")
			(hide yes)
			(effects
				(font
					(size 1.27 1.27)
				)
			)
		)
		(property "Value" ""
			(at 0 0 270)
			(layer "F.Fab")
			(effects
				(font
					(size 1.27 1.27)
				)
			)
		)
		(duplicate_pad_numbers_are_jumpers no)
		(fp_line
			(start -0.299974 0.150114)
			(end -0.299974 -0.150114)
			(stroke
				(width 0.1)
				(type default)
			)
			(layer "F.Fab")
		)
		(fp_line
			(start 0.299974 0.150114)
			(end -0.299974 0.150114)
			(stroke
				(width 0.1)
				(type default)
			)
			(layer "F.Fab")
		)
		(fp_line
			(start -0.299974 -0.150114)
			(end 0.299974 -0.150114)
			(stroke
				(width 0.1)
				(type default)
			)
			(layer "F.Fab")
		)
		(fp_line
			(start 0.299974 -0.150114)
			(end 0.299974 0.150114)
			(stroke
				(width 0.1)
				(type default)
			)
			(layer "F.Fab")
		)
		(pad "1" smd rect
			(at -0.2667 0 270)
			(size 0.3048 0.381)
			(layers "F.Cu" "F.Mask" "F.Paste")
			(net "P5E_CPU0_P3_TX_C_DP<6>")
		)
		(pad "2" smd rect
			(at 0.2667 0 270)
			(size 0.3048 0.381)
			(layers "F.Cu" "F.Mask" "F.Paste")
			(net "P5E_CPU0_P3_TX_DP<6>")
		)
	)
)
